# S9S_MB_2U (Grand Teton) — schematic netlist excerpt (pin names and nets, part order shuffled) for the footprints in the layout excerpt that follows; sources: Cadence DE-HDL packaged netlist, KiCad conversion of 03242023_DA0F0TMBIJ0_F0T_Motherboard_J_brd_V01_OCP.brd

J31  SCONN288_ADR50017P130CC  SCONN288_ADR50017-P130CC IO  pkg DDR288S_1-1VXB  page 112
  VIN_BULK0  = P12V_S3_AUX_CPU1_NVDIMM
  RFU0  = TP_CHH_CPU1_DIMM1_FRU_0
  VIN_MGMT  = P3V3_AUX
  HSCL  = I3C_SPD_DDREFGH_CPU1_LVC1_SCL_6
  HSDA  = I3C_SPD_DDREFGH_CPU1_LVC1_SDA
  VSS0  = GND
  DQ0_A  = M_H_CPU1_SA_DQ<0>
  VSS1  = GND
  DQ1_A  = M_H_CPU1_SA_DQ<1>
  VSS2  = GND
  DQS0_A_T  = M_H_CPU1_SA_DQS_DP<0>
  DQS0_A_C  = M_H_CPU1_SA_DQS_DN<0>
  VSS3  = GND
  DQ4_A  = M_H_CPU1_SA_DQ<4>
  VSS4  = GND
  DQ5_A  = M_H_CPU1_SA_DQ<5>
  VSS5  = GND
  DQ8_A  = M_H_CPU1_SA_DQ<8>
  VSS6  = GND
  DQ9_A  = M_H_CPU1_SA_DQ<9>
  VSS7  = GND
  DQS1_A_T  = M_H_CPU1_SA_DQS_DP<1>
  DQS1_A_C  = M_H_CPU1_SA_DQS_DN<1>
  VSS8  = GND
  DQ12_A  = M_H_CPU1_SA_DQ<12>
  VSS9  = GND
  DQ13_A  = M_H_CPU1_SA_DQ<13>
  VSS10  = GND
  DQ16_A  = M_H_CPU1_SA_DQ<16>
  VSS11  = GND
  DQ17_A  = M_H_CPU1_SA_DQ<17>
  VSS12  = GND
  DQS2_A_T  = M_H_CPU1_SA_DQS_DP<2>
  DQS2_A_C  = M_H_CPU1_SA_DQS_DN<2>
  VSS13  = GND
  DQ20_A  = M_H_CPU1_SA_DQ<20>
  VSS14  = GND
  DQ21_A  = M_H_CPU1_SA_DQ<21>
  VSS15  = GND
  DQ24_A  = M_H_CPU1_SA_DQ<24>
  VSS16  = GND
  DQ25_A  = M_H_CPU1_SA_DQ<25>
  VSS17  = GND
  DQS3_A_T  = M_H_CPU1_SA_DQS_DP<3>
  DQS3_A_C  = M_H_CPU1_SA_DQS_DN<3>
  VSS18  = GND
  DQ28_A  = M_H_CPU1_SA_DQ<28>
  VSS19  = GND
  DQ29_A  = M_H_CPU1_SA_DQ<29>
  VSS20  = GND
  CB0_A  = M_H_CPU1_SA_CB<0>
  VSS21  = GND
  CB1_A  = M_H_CPU1_SA_CB<1>
  VSS22  = GND
  DQS4_A_T  = M_H_CPU1_SA_DQS_DP<4>
  DQS4_A_C  = M_H_CPU1_SA_DQS_DN<4>
  VSS23  = GND
  CB4_A  = M_H_CPU1_SA_CB<4>
  VSS24  = GND
  CB5_A  = M_H_CPU1_SA_CB<5>
  VSS25  = GND
  ALERT_N  = M_H_CPU1_ALERT_N
  VSS26  = GND
  CS0_A_N  = M_H_CPU1_SA_CS_N<0>
  VSS27  = GND
  CA0_A  = M_H_CPU1_SA_CA<0>
  VSS28  = GND
  CA2_A  = M_H_CPU1_SA_CA<2>
  VSS29  = GND
  CA4_A  = M_H_CPU1_SA_CA<4>
  VSS30  = GND
  CA6_A  = M_H_CPU1_SA_CA<6>
  VSS31  = GND
  PAR_A  = M_H_CPU1_SA_PAR
  VSS32  = GND
  CA0_B  = M_H_CPU1_SB_CA<0>
  VSS33  = GND
  CA2_B  = M_H_CPU1_SB_CA<2>
  VSS34  = GND
  CA4_B  = M_H_CPU1_SB_CA<4>
  VSS35  = GND
  CA6_B  = M_H_CPU1_SB_CA<6>
  VSS36  = GND
  CS0_B_N  = M_H_CPU1_SB_CS_N<0>
  VSS37  = GND
  \lbd||rsp_a_n\  = M_H_CPU1_SA_RSP<0>
  \lbs||rsp_b_n\  = M_H_CPU1_SB_RSP<0>
  VSS38  = GND
  CB4_B  = M_H_CPU1_SB_CB<4>
  VSS39  = GND
  CB5_B  = M_H_CPU1_SB_CB<5>
  VSS40  = GND
  \dqs9_b_t||tdqs9_b_t||dbi4_b_n\  = M_H_CPU1_SB_DQS_DP<9>
  \dqs9_b_c||tdqs9_b_c\  = M_H_CPU1_SB_DQS_DN<9>
  VSS41  = GND
  CB0_B  = M_H_CPU1_SB_CB<0>
  VSS42  = GND
  CB1_B  = M_H_CPU1_SB_CB<1>
  VSS43  = GND
  DQ0_B  = M_H_CPU1_SB_DQ<0>
  VSS44  = GND
  DQ1_B  = M_H_CPU1_SB_DQ<1>
  VSS45  = GND
  DQS0_B_T  = M_H_CPU1_SB_DQS_DP<0>
  DQS0_B_C  = M_H_CPU1_SB_DQS_DN<0>
  VSS46  = GND
  DQ4_B  = M_H_CPU1_SB_DQ<4>
  VSS47  = GND
  DQ5_B  = M_H_CPU1_SB_DQ<5>
  VSS48  = GND
  DQ8_B  = M_H_CPU1_SB_DQ<8>
  VSS49  = GND
  DQ9_B  = M_H_CPU1_SB_DQ<9>
  VSS50  = GND
  DQS1_B_T  = M_H_CPU1_SB_DQS_DP<1>
  DQS1_B_C  = M_H_CPU1_SB_DQS_DN<1>
  VSS51  = GND
  DQ12_B  = M_H_CPU1_SB_DQ<12>
  VSS52  = GND
  DQ13_B  = M_H_CPU1_SB_DQ<13>
  VSS53  = GND
  DQ16_B  = M_H_CPU1_SB_DQ<16>
  VSS54  = GND
  DQ17_B  = M_H_CPU1_SB_DQ<17>
  VSS55  = GND
  DQS2_B_T  = M_H_CPU1_SB_DQS_DP<2>
  DQS2_B_C  = M_H_CPU1_SB_DQS_DN<2>
  VSS56  = GND
  DQ20_B  = M_H_CPU1_SB_DQ<20>
  VSS57  = GND
  DQ21_B  = M_H_CPU1_SB_DQ<21>
  VSS58  = GND
  DQ24_B  = M_H_CPU1_SB_DQ<24>
  VSS59  = GND
  DQ25_B  = M_H_CPU1_SB_DQ<25>
  VSS60  = GND
  DQS3_B_T  = M_H_CPU1_SB_DQS_DP<3>
  DQS3_B_C  = M_H_CPU1_SB_DQS_DN<3>
  VSS61  = GND
  DQ28_B  = M_H_CPU1_SB_DQ<28>
  VSS62  = GND
  DQ29_B  = M_H_CPU1_SB_DQ<29>
  VSS63  = GND
  RFU1  = TP_CHH_CPU1_DIMM1_FRU_1
  VIN_BULK1  = P12V_S3_AUX_CPU1_NVDIMM
  VIN_BULK2  = P12V_S3_AUX_CPU1_NVDIMM
  \pwr_good||fail_n\  = PWRGD_CHH_CPU1_DIMM1
  HSA  = PD_CHH_CPU1_DIMM1_SAA
  RFU2  = TP_CHH_CPU1_DIMM1_FRU_2
  RFU3  = TP_CHH_CPU1_DIMM1_FRU_3
  VSS64  = GND
  DQ2_A  = M_H_CPU1_SA_DQ<2>
  VSS65  = GND
  DQ3_A  = M_H_CPU1_SA_DQ<3>
  VSS66  = GND
  \dqs5_a_c||tdqs5_a_c||dqs5_a_t||tdqs5_a_t\  = M_H_CPU1_SA_DQS_DN<5>
  \dqs5_a_t||tdqs5_a_t\  = M_H_CPU1_SA_DQS_DP<5>
  VSS67  = GND
  DQ6_A  = M_H_CPU1_SA_DQ<6>
  VSS68  = GND
  DQ7_A  = M_H_CPU1_SA_DQ<7>
  VSS69  = GND
  DQ10_A  = M_H_CPU1_SA_DQ<10>
  VSS70  = GND
  DQ11_A  = M_H_CPU1_SA_DQ<11>
  VSS71  = GND
  \dqs6_a_c||tdqs6_a_c||dqs6_a_t||tdqs6_a_t\  = M_H_CPU1_SA_DQS_DN<6>
  \dqs6_a_t||tdqs6_a_t\  = M_H_CPU1_SA_DQS_DP<6>
  VSS72  = GND
  DQ14_A  = M_H_CPU1_SA_DQ<14>
  VSS73  = GND
  DQ15_A  = M_H_CPU1_SA_DQ<15>
  VSS74  = GND
  DQ18_A  = M_H_CPU1_SA_DQ<18>
  VSS75  = GND
  DQ19_A  = M_H_CPU1_SA_DQ<19>
  VSS76  = GND
  \dqs7_a_c||tdqs7_a_c\  = M_H_CPU1_SA_DQS_DN<7>
  \dqs7_a_t||tdqs7_a_t\  = M_H_CPU1_SA_DQS_DP<7>
  VSS77  = GND
  DQ22_A  = M_H_CPU1_SA_DQ<22>
  VSS78  = GND
  DQ23_A  = M_H_CPU1_SA_DQ<23>
  VSS79  = GND
  DQ26_A  = M_H_CPU1_SA_DQ<26>
  VSS80  = GND
  DQ27_A  = M_H_CPU1_SA_DQ<27>
  VSS81  = GND
  \dqs8_a_c||tdqs8_a_c\  = M_H_CPU1_SA_DQS_DN<8>
  \dqs8_a_t||tdqs8_a_t\  = M_H_CPU1_SA_DQS_DP<8>
  VSS82  = GND
  DQ30_A  = M_H_CPU1_SA_DQ<30>
  VSS83  = GND
  DQ31_A  = M_H_CPU1_SA_DQ<31>
  VSS84  = GND
  CB2_A  = M_H_CPU1_SA_CB<2>
  VSS85  = GND
  CB3_A  = M_H_CPU1_SA_CB<3>
  VSS86  = GND
  \dqs9_a_c||tdqs9_a_c\  = M_H_CPU1_SA_DQS_DN<9>
  \dqs9_a_t||tdqs9_a_t\  = M_H_CPU1_SA_DQS_DP<9>
  VSS87  = GND
  CB6_A  = M_H_CPU1_SA_CB<6>
  VSS88  = GND
  CB7_A  = M_H_CPU1_SA_CB<7>
  VSS89  = GND
  RESET_N  = RST_M_GH_CPU1_FPGA_N
  VSS90  = GND
  CS1_A_N  = M_H_CPU1_SA_CS_N<1>
  VSS91  = GND
  CA1_A  = M_H_CPU1_SA_CA<1>
  VSS92  = GND
  CA3_A  = M_H_CPU1_SA_CA<3>
  VSS93  = GND
  CA5_A  = M_H_CPU1_SA_CA<5>
  VSS94  = GND
  CK_T  = M_H_CPU1_CLK_DP<0>
  CK_C  = M_H_CPU1_CLK_DN<0>
  VSS95  = GND
  RFU4  = TP_CHH_CPU1_DIMM1_FRU_4
  CA1_B  = M_H_CPU1_SB_CA<1>
  VSS96  = GND
  CA3_B  = M_H_CPU1_SB_CA<3>
  VSS97  = GND
  CA5_B  = M_H_CPU1_SB_CA<5>
  VSS98  = GND
  PAR_B  = M_H_CPU1_SB_PAR
  VSS99  = GND
  CS1_B_N  = M_H_CPU1_SB_CS_N<1>
  VSS100  = GND
  RFU5  = TP_CHH_CPU1_DIMM1_FRU_5
  RFU6  = TP_CHH_CPU1_DIMM1_FRU_6
  VSS101  = GND
  CB6_B  = M_H_CPU1_SB_CB<6>
  VSS102  = GND
  CB7_B  = M_H_CPU1_SB_CB<7>
  VSS103  = GND
  DQS4_B_C  = M_H_CPU1_SB_DQS_DN<4>
  DQS4_B_T  = M_H_CPU1_SB_DQS_DP<4>
  VSS104  = GND
  CB2_B  = M_H_CPU1_SB_CB<2>
  VSS105  = GND
  CB3_B  = M_H_CPU1_SB_CB<3>
  VSS106  = GND
  DQ2_B  = M_H_CPU1_SB_DQ<2>
  VSS107  = GND
  DQ3_B  = M_H_CPU1_SB_DQ<3>
  VSS108  = GND
  \dqs5_b_c||tdqs5_b_c\  = M_H_CPU1_SB_DQS_DN<5>
  \dqs5_b_t||tdqs5_b_t\  = M_H_CPU1_SB_DQS_DP<5>
  VSS109  = GND
  DQ6_B  = M_H_CPU1_SB_DQ<6>
  VSS110  = GND
  DQ7_B  = M_H_CPU1_SB_DQ<7>
  VSS111  = GND
  DQ10_B  = M_H_CPU1_SB_DQ<10>
  VSS112  = GND
  DQ11_B  = M_H_CPU1_SB_DQ<11>
  VSS113  = GND
  \dqs6_b_c||tdqs6_b_c\  = M_H_CPU1_SB_DQS_DN<6>
  \dqs6_b_t||tdqs6_b_t\  = M_H_CPU1_SB_DQS_DP<6>
  VSS114  = GND
  DQ14_B  = M_H_CPU1_SB_DQ<14>
  VSS115  = GND
  DQ15_B  = M_H_CPU1_SB_DQ<15>
  VSS116  = GND
  DQ18_B  = M_H_CPU1_SB_DQ<18>
  VSS117  = GND
  DQ19_B  = M_H_CPU1_SB_DQ<19>
  VSS118  = GND
  \dqs7_b_c||tdqs7_b_c\  = M_H_CPU1_SB_DQS_DN<7>
  \dqs7_b_t||tdqs7_b_t\  = M_H_CPU1_SB_DQS_DP<7>
  VSS119  = GND
  DQ22_B  = M_H_CPU1_SB_DQ<22>
  VSS120  = GND
  DQ23_B  = M_H_CPU1_SB_DQ<23>
  VSS121  = GND
  DQ26_B  = M_H_CPU1_SB_DQ<26>
  VSS122  = GND
  DQ27_B  = M_H_CPU1_SB_DQ<27>
  VSS123  = GND
  \dqs8_b_c||tdqs8_b_c\  = M_H_CPU1_SB_DQS_DN<8>
  \dqs8_b_t||tdqs8_b_t\  = M_H_CPU1_SB_DQS_DP<8>
  VSS124  = GND
  DQ30_B  = M_H_CPU1_SB_DQ<30>
  VSS125  = GND
  DQ31_B  = M_H_CPU1_SB_DQ<31>
  VSS126  = GND
  G1  = GND
  G2  = GND
  G3  = GND

(kicad_pcb
	(version 20260206)
	(generator "pcbnew")
	(generator_version "10.0")
	(general
		(thickness 1.6)
		(legacy_teardrops no)
	)
	(paper "A4")
	(title_block
		(title "03242023_DA0F0TMBIJ0_F0T_Motherboard_J_brd_V01_OCP.brd")
		(comment 1 "Grand Teton / footprint 3900 of 6105 (J31), pads 1-45 of 291")
	)
	(layers
		(0 "F.Cu" signal "TOP")
		(4 "In1.Cu" signal "GND")
		(6 "In2.Cu" signal "IN1")
		(8 "In3.Cu" signal "GND1")
		(10 "In4.Cu" signal "IN2")
		(12 "In5.Cu" signal "GND2")
		(14 "In6.Cu" signal "IN3")
		(16 "In7.Cu" signal "GND3")
		(18 "In8.Cu" signal "VCC")
		(20 "In9.Cu" signal "VCC1")
		(22 "In10.Cu" signal "GND4")
		(24 "In11.Cu" signal "IN4")
		(26 "In12.Cu" signal "GND5")
		(28 "In13.Cu" signal "IN5")
		(30 "In14.Cu" signal "GND6")
		(32 "In15.Cu" signal "IN6")
		(34 "In16.Cu" signal "GND7")
		(2 "B.Cu" signal "BOTTOM")
		(9 "F.Adhes" user "F.Adhesive")
		(11 "B.Adhes" user "B.Adhesive")
		(13 "F.Paste" user "Package Geometry/Pastemask Top")
		(15 "B.Paste" user "Package Geometry/Pastemask Bottom")
		(5 "F.SilkS" user "Ref Des/Silkscreen Top")
		(7 "B.SilkS" user "Ref Des/Silkscreen Bottom")
		(1 "F.Mask" user "Board Geometry/Soldermask Top")
		(3 "B.Mask" user "Board Geometry/Soldermask Bottom")
		(17 "Dwgs.User" user "User.Drawings")
		(19 "Cmts.User" user "User.Comments")
		(21 "Eco1.User" user "User.Eco1")
		(23 "Eco2.User" user "User.Eco2")
		(25 "Edge.Cuts" user "Board Geometry/Outline")
		(27 "Margin" user)
		(31 "F.CrtYd" user "Package Geometry/Place Bound Top")
		(29 "B.CrtYd" user "Package Geometry/Place Bound Bottom")
		(35 "F.Fab" user "Ref Des/Assembly Top")
		(33 "B.Fab" user "Ref Des/Assembly Bottom")
	)
	(footprint ""
		(layer "F.Cu")
		(at 213.66988 -258.091686)
		(property "Reference" "J31"
			(at -3.683 -81.702148 0)
			(unlocked yes)
			(layer "F.SilkS")
			(effects
				(font
					(size 0.7874 0.5842)
					(thickness 0.1524)
				)
				(justify left)
			)
		)
		(property "Value" ""
			(at 0 0 0)
			(layer "F.Fab")
			(effects
				(font
					(size 1.27 1.27)
				)
			)
		)
		(duplicate_pad_numbers_are_jumpers no)
		(pad "1" smd rect
			(at -2.050034 -63.324994 270)
			(size 0.519938 1.4986)
			(layers "F.Cu" "F.Mask" "F.Paste")
			(net "P12V_S3_AUX_CPU1_NVDIMM")
		)
		(pad "2" smd rect
			(at -2.050034 -62.47511 270)
			(size 0.519938 1.4986)
			(layers "F.Cu" "F.Mask" "F.Paste")
			(net "TP_CHH_CPU1_DIMM1_FRU_0")
		)
		(pad "3" smd rect
			(at -2.050034 -61.624972 270)
			(size 0.519938 1.4986)
			(layers "F.Cu" "F.Mask" "F.Paste")
			(net "P3V3_AUX")
		)
		(pad "4" smd rect
			(at -2.050034 -60.775088 270)
			(size 0.519938 1.4986)
			(layers "F.Cu" "F.Mask" "F.Paste")
			(net "I3C_SPD_DDREFGH_CPU1_LVC1_SCL_6")
		)
		(pad "5" smd rect
			(at -2.050034 -59.92495 270)
			(size 0.519938 1.4986)
			(layers "F.Cu" "F.Mask" "F.Paste")
			(net "I3C_SPD_DDREFGH_CPU1_LVC1_SDA")
		)
		(pad "6" smd rect
			(at -2.050034 -59.075066 270)
			(size 0.519938 1.4986)
			(layers "F.Cu" "F.Mask" "F.Paste")
			(net "GND")
		)
		(pad "7" smd rect
			(at -2.050034 -58.224928 270)
			(size 0.519938 1.4986)
			(layers "F.Cu" "F.Mask" "F.Paste")
			(net "M_H_CPU1_SA_DQ<0>")
		)
		(pad "8" smd rect
			(at -2.050034 -57.375044 270)
			(size 0.519938 1.4986)
			(layers "F.Cu" "F.Mask" "F.Paste")
			(net "GND")
		)
		(pad "9" smd rect
			(at -2.050034 -56.524906 270)
			(size 0.519938 1.4986)
			(layers "F.Cu" "F.Mask" "F.Paste")
			(net "M_H_CPU1_SA_DQ<1>")
		)
		(pad "10" smd rect
			(at -2.050034 -55.675022 270)
			(size 0.519938 1.4986)
			(layers "F.Cu" "F.Mask" "F.Paste")
			(net "GND")
		)
		(pad "11" smd rect
			(at -2.050034 -54.824884 270)
			(size 0.519938 1.4986)
			(layers "F.Cu" "F.Mask" "F.Paste")
			(net "M_H_CPU1_SA_DQS_DP<0>")
		)
		(pad "12" smd rect
			(at -2.050034 -53.975 270)
			(size 0.519938 1.4986)
			(layers "F.Cu" "F.Mask" "F.Paste")
			(net "M_H_CPU1_SA_DQS_DN<0>")
		)
		(pad "13" smd rect
			(at -2.050034 -53.125116 270)
			(size 0.519938 1.4986)
			(layers "F.Cu" "F.Mask" "F.Paste")
			(net "GND")
		)
		(pad "14" smd rect
			(at -2.050034 -52.274978 270)
			(size 0.519938 1.4986)
			(layers "F.Cu" "F.Mask" "F.Paste")
			(net "M_H_CPU1_SA_DQ<4>")
		)
		(pad "15" smd rect
			(at -2.050034 -51.425094 270)
			(size 0.519938 1.4986)
			(layers "F.Cu" "F.Mask" "F.Paste")
			(net "GND")
		)
		(pad "16" smd rect
			(at -2.050034 -50.574956 270)
			(size 0.519938 1.4986)
			(layers "F.Cu" "F.Mask" "F.Paste")
			(net "M_H_CPU1_SA_DQ<5>")
		)
		(pad "17" smd rect
			(at -2.050034 -49.725072 270)
			(size 0.519938 1.4986)
			(layers "F.Cu" "F.Mask" "F.Paste")
			(net "GND")
		)
		(pad "18" smd rect
			(at -2.050034 -48.874934 270)
			(size 0.519938 1.4986)
			(layers "F.Cu" "F.Mask" "F.Paste")
			(net "M_H_CPU1_SA_DQ<8>")
		)
		(pad "19" smd rect
			(at -2.050034 -48.02505 270)
			(size 0.519938 1.4986)
			(layers "F.Cu" "F.Mask" "F.Paste")
			(net "GND")
		)
		(pad "20" smd rect
			(at -2.050034 -47.174912 270)
			(size 0.519938 1.4986)
			(layers "F.Cu" "F.Mask" "F.Paste")
			(net "M_H_CPU1_SA_DQ<9>")
		)
		(pad "21" smd rect
			(at -2.050034 -46.325028 270)
			(size 0.519938 1.4986)
			(layers "F.Cu" "F.Mask" "F.Paste")
			(net "GND")
		)
		(pad "22" smd rect
			(at -2.050034 -45.47489 270)
			(size 0.519938 1.4986)
			(layers "F.Cu" "F.Mask" "F.Paste")
			(net "M_H_CPU1_SA_DQS_DP<1>")
		)
		(pad "23" smd rect
			(at -2.050034 -44.625006 270)
			(size 0.519938 1.4986)
			(layers "F.Cu" "F.Mask" "F.Paste")
			(net "M_H_CPU1_SA_DQS_DN<1>")
		)
		(pad "24" smd rect
			(at -2.050034 -43.775122 270)
			(size 0.519938 1.4986)
			(layers "F.Cu" "F.Mask" "F.Paste")
			(net "GND")
		)
		(pad "25" smd rect
			(at -2.050034 -42.924984 270)
			(size 0.519938 1.4986)
			(layers "F.Cu" "F.Mask" "F.Paste")
			(net "M_H_CPU1_SA_DQ<12>")
		)
		(pad "26" smd rect
			(at -2.050034 -42.0751 270)
			(size 0.519938 1.4986)
			(layers "F.Cu" "F.Mask" "F.Paste")
			(net "GND")
		)
		(pad "27" smd rect
			(at -2.050034 -41.224962 270)
			(size 0.519938 1.4986)
			(layers "F.Cu" "F.Mask" "F.Paste")
			(net "M_H_CPU1_SA_DQ<13>")
		)
		(pad "28" smd rect
			(at -2.050034 -40.375078 270)
			(size 0.519938 1.4986)
			(layers "F.Cu" "F.Mask" "F.Paste")
			(net "GND")
		)
		(pad "29" smd rect
			(at -2.050034 -39.52494 270)
			(size 0.519938 1.4986)
			(layers "F.Cu" "F.Mask" "F.Paste")
			(net "M_H_CPU1_SA_DQ<16>")
		)
		(pad "30" smd rect
			(at -2.050034 -38.675056 270)
			(size 0.519938 1.4986)
			(layers "F.Cu" "F.Mask" "F.Paste")
			(net "GND")
		)
		(pad "31" smd rect
			(at -2.050034 -37.824918 270)
			(size 0.519938 1.4986)
			(layers "F.Cu" "F.Mask" "F.Paste")
			(net "M_H_CPU1_SA_DQ<17>")
		)
		(pad "32" smd rect
			(at -2.050034 -36.975034 270)
			(size 0.519938 1.4986)
			(layers "F.Cu" "F.Mask" "F.Paste")
			(net "GND")
		)
		(pad "33" smd rect
			(at -2.050034 -36.124896 270)
			(size 0.519938 1.4986)
			(layers "F.Cu" "F.Mask" "F.Paste")
			(net "M_H_CPU1_SA_DQS_DP<2>")
		)
		(pad "34" smd rect
			(at -2.050034 -35.275012 270)
			(size 0.519938 1.4986)
			(layers "F.Cu" "F.Mask" "F.Paste")
			(net "M_H_CPU1_SA_DQS_DN<2>")
		)
		(pad "35" smd rect
			(at -2.050034 -34.425128 270)
			(size 0.519938 1.4986)
			(layers "F.Cu" "F.Mask" "F.Paste")
			(net "GND")
		)
		(pad "36" smd rect
			(at -2.050034 -33.57499 270)
			(size 0.519938 1.4986)
			(layers "F.Cu" "F.Mask" "F.Paste")
			(net "M_H_CPU1_SA_DQ<20>")
		)
		(pad "37" smd rect
			(at -2.050034 -32.725106 270)
			(size 0.519938 1.4986)
			(layers "F.Cu" "F.Mask" "F.Paste")
			(net "GND")
		)
		(pad "38" smd rect
			(at -2.050034 -31.874968 270)
			(size 0.519938 1.4986)
			(layers "F.Cu" "F.Mask" "F.Paste")
			(net "M_H_CPU1_SA_DQ<21>")
		)
		(pad "39" smd rect
			(at -2.050034 -31.025084 270)
			(size 0.519938 1.4986)
			(layers "F.Cu" "F.Mask" "F.Paste")
			(net "GND")
		)
		(pad "40" smd rect
			(at -2.050034 -30.174946 270)
			(size 0.519938 1.4986)
			(layers "F.Cu" "F.Mask" "F.Paste")
			(net "M_H_CPU1_SA_DQ<24>")
		)
		(pad "41" smd rect
			(at -2.050034 -29.325062 270)
			(size 0.519938 1.4986)
			(layers "F.Cu" "F.Mask" "F.Paste")
			(net "GND")
		)
		(pad "42" smd rect
			(at -2.050034 -28.474924 270)
			(size 0.519938 1.4986)
			(layers "F.Cu" "F.Mask" "F.Paste")
			(net "M_H_CPU1_SA_DQ<25>")
		)
		(pad "43" smd rect
			(at -2.050034 -27.62504 270)
			(size 0.519938 1.4986)
			(layers "F.Cu" "F.Mask" "F.Paste")
			(net "GND")
		)
		(pad "44" smd rect
			(at -2.050034 -26.774902 270)
			(size 0.519938 1.4986)
			(layers "F.Cu" "F.Mask" "F.Paste")
			(net "M_H_CPU1_SA_DQS_DP<3>")
		)
		(pad "45" smd rect
			(at -2.050034 -25.925018 270)
			(size 0.519938 1.4986)
			(layers "F.Cu" "F.Mask" "F.Paste")
			(net "M_H_CPU1_SA_DQS_DN<3>")
		)
	)
)
